FILE_TYPE = CONNECTIVITY;
{Allegro Design Entry HDL 16.6-p007 (v16-6-112F) 10/10/2012}
"PAGE_NUMBER" = 105;
0"NC";
1"P3E_CPU0_PE2_SS_C_TXP<15:0>";
2"P3E_CPU0_PE1_PCH_R_RXP<15:8>";
3"P3E_CPU0_PE1_PCH_R_RXN<15:8>";
4"P3E_CPU0_PE2_SS_C_TXN<15:0>";
5"P3E_CPU0_PE1_PCH_RXP<15:8>";
6"P3E_CPU0_PE1_PCH_RXN<15:8>";
7"P3E_CPU0_PE2_SS_TXP<15:0>";
8"P3E_CPU0_PE2_SS_TXN<15:0>";
9"P3E_CPU0_PE1_PCH_TXN<15:8>";
10"P3E_CPU0_PE1_PCH_TXP<15:8>";
11"P3E_CPU0_PE1_PCH_C_TXN<15:8>";
12"P3E_CPU0_PE1_PCH_C_TXP<15:8>";
13"P3E_CPU0_PE1_PCH_C_TXP<15>";
14"P3E_CPU0_PE1_PCH_C_TXP<13>";
15"P3E_CPU0_PE1_PCH_C_TXP<14>";
16"P3E_CPU0_PE1_PCH_C_TXP<12>";
17"P3E_CPU0_PE1_PCH_TXP<15>";
18"P3E_CPU0_PE1_PCH_C_TXN<15>";
19"P3E_CPU0_PE1_PCH_TXP<14>";
20"P3E_CPU0_PE1_PCH_TXP<13>";
21"P3E_CPU0_PE1_PCH_TXP<12>";
22"P3E_CPU0_PE1_PCH_C_TXN<13>";
23"P3E_CPU0_PE1_PCH_C_TXN<12>";
24"P3E_CPU0_PE1_PCH_C_TXN<14>";
25"P3E_CPU0_PE1_PCH_TXN<15>";
26"P3E_CPU0_PE1_PCH_TXN<13>";
27"P3E_CPU0_PE1_PCH_TXN<14>";
28"P3E_CPU0_PE1_PCH_TXN<12>";
29"P3E_CPU0_PE1_PCH_C_TXP<11>";
30"P3E_CPU0_PE1_PCH_C_TXP<9>";
31"P3E_CPU0_PE1_PCH_C_TXP<8>";
32"P3E_CPU0_PE1_PCH_C_TXP<10>";
33"P3E_CPU0_PE1_PCH_TXP<11>";
34"P3E_CPU0_PE1_PCH_TXP<10>";
35"P3E_CPU0_PE1_PCH_C_TXN<11>";
36"P3E_CPU0_PE1_PCH_C_TXN<9>";
37"P3E_CPU0_PE1_PCH_TXP<9>";
38"P3E_CPU0_PE1_PCH_TXP<8>";
39"P3E_CPU0_PE1_PCH_C_TXN<8>";
40"P3E_CPU0_PE1_PCH_C_TXN<10>";
41"P3E_CPU0_PE1_PCH_TXN<11>";
42"P3E_CPU0_PE1_PCH_TXN<9>";
43"P3E_CPU0_PE1_PCH_TXN<10>";
44"P3E_CPU0_PE1_PCH_TXN<8>";
45"P3E_CPU0_PE2_SS_C_TXN<15>";
46"P3E_CPU0_PE2_SS_TXN<15>";
47"P3E_CPU0_PE2_SS_C_TXN<13>";
48"P3E_CPU0_PE2_SS_C_TXN<14>";
49"P3E_CPU0_PE2_SS_C_TXN<12>";
50"P3E_CPU0_PE2_SS_TXN<13>";
51"P3E_CPU0_PE2_SS_TXN<14>";
52"P3E_CPU0_PE2_SS_TXN<12>";
53"P3E_CPU0_PE2_SS_C_TXP<15>";
54"P3E_CPU0_PE2_SS_C_TXP<14>";
55"P3E_CPU0_PE2_SS_TXP<15>";
56"P3E_CPU0_PE2_SS_TXP<14>";
57"P3E_CPU0_PE2_SS_C_TXP<13>";
58"P3E_CPU0_PE2_SS_C_TXP<12>";
59"P3E_CPU0_PE2_SS_TXP<13>";
60"P3E_CPU0_PE2_SS_TXP<12>";
61"P3E_CPU0_PE1_PCH_RXP<15>";
62"P3E_CPU0_PE1_PCH_RXN<15>";
63"P3E_CPU0_PE1_PCH_RXN<13>";
64"P3E_CPU0_PE1_PCH_RXN<11>";
65"P3E_CPU0_PE1_PCH_RXN<12>";
66"P3E_CPU0_PE1_PCH_RXN<14>";
67"P3E_CPU0_PE1_PCH_R_RXN<15>";
68"P3E_CPU0_PE1_PCH_R_RXN<14>";
69"P3E_CPU0_PE1_PCH_R_RXN<13>";
70"P3E_CPU0_PE1_PCH_RXP<13>";
71"P3E_CPU0_PE1_PCH_R_RXN<12>";
72"P3E_CPU0_PE1_PCH_R_RXN<11>";
73"P3E_CPU0_PE1_PCH_RXP<11>";
74"P3E_CPU0_PE1_PCH_RXP<12>";
75"P3E_CPU0_PE1_PCH_RXP<14>";
76"P3E_CPU0_PE1_PCH_RXP<10>";
77"P3E_CPU0_PE1_PCH_R_RXP<15>";
78"P3E_CPU0_PE2_SS_C_TXN<11>";
79"P3E_CPU0_PE2_SS_C_TXN<9>";
80"P3E_CPU0_PE2_SS_C_TXN<10>";
81"P3E_CPU0_PE2_SS_TXN<9>";
82"P3E_CPU0_PE2_SS_TXN<11>";
83"P3E_CPU0_PE2_SS_TXN<10>";
84"P3E_CPU0_PE2_SS_C_TXN<8>";
85"P3E_CPU0_PE2_SS_C_TXN<7>";
86"P3E_CPU0_PE2_SS_TXN<7>";
87"P3E_CPU0_PE2_SS_TXN<8>";
88"P3E_CPU0_PE1_PCH_R_RXP<14>";
89"P3E_CPU0_PE1_PCH_R_RXP<13>";
90"P3E_CPU0_PE1_PCH_R_RXP<12>";
91"P3E_CPU0_PE1_PCH_R_RXP<11>";
92"P3E_CPU0_PE1_PCH_R_RXP<10>";
93"P3E_CPU0_PE2_SS_C_TXN<6>";
94"P3E_CPU0_PE2_SS_C_TXN<5>";
95"P3E_CPU0_PE2_SS_C_TXN<4>";
96"P3E_CPU0_PE2_SS_TXN<5>";
97"P3E_CPU0_PE2_SS_TXN<6>";
98"P3E_CPU0_PE2_SS_TXN<4>";
99"P3E_CPU0_PE2_SS_C_TXN<3>";
100"P3E_CPU0_PE2_SS_C_TXN<2>";
101"P3E_CPU0_PE2_SS_TXN<3>";
102"P3E_CPU0_PE2_SS_TXN<2>";
103"P3E_CPU0_PE1_PCH_RXN<9>";
104"P3E_CPU0_PE1_PCH_RXN<8>";
105"P3E_CPU0_PE1_PCH_RXN<10>";
106"P3E_CPU0_PE1_PCH_R_RXN<9>";
107"P3E_CPU0_PE1_PCH_R_RXN<10>";
108"P3E_CPU0_PE1_PCH_R_RXN<8>";
109"P3E_CPU0_PE1_PCH_RXP<9>";
110"P3E_CPU0_PE1_PCH_RXP<8>";
111"P3E_CPU0_PE1_PCH_R_RXP<9>";
112"P3E_CPU0_PE1_PCH_R_RXP<8>";
113"P3E_CPU0_PE2_SS_C_TXN<1>";
114"P3E_CPU0_PE2_SS_C_TXN<0>";
115"P3E_CPU0_PE2_SS_TXN<1>";
116"P3E_CPU0_PE2_SS_TXN<0>";
117"P3E_CPU0_PE2_SS_C_TXP<11>";
118"P3E_CPU0_PE2_SS_C_TXP<10>";
119"P3E_CPU0_PE2_SS_C_TXP<9>";
120"P3E_CPU0_PE2_SS_TXP<9>";
121"P3E_CPU0_PE2_SS_TXP<11>";
122"P3E_CPU0_PE2_SS_TXP<10>";
123"P3E_CPU0_PE2_SS_C_TXP<8>";
124"P3E_CPU0_PE2_SS_C_TXP<7>";
125"P3E_CPU0_PE2_SS_TXP<7>";
126"P3E_CPU0_PE2_SS_TXP<8>";
127"P3E_CPU0_PE2_SS_C_TXP<5>";
128"P3E_CPU0_PE2_SS_C_TXP<6>";
129"P3E_CPU0_PE2_SS_C_TXP<4>";
130"P3E_CPU0_PE2_SS_TXP<5>";
131"P3E_CPU0_PE2_SS_TXP<6>";
132"P3E_CPU0_PE2_SS_TXP<4>";
133"P3E_CPU0_PE2_SS_C_TXP<3>";
134"P3E_CPU0_PE2_SS_C_TXP<2>";
135"P3E_CPU0_PE2_SS_TXP<3>";
136"P3E_CPU0_PE2_SS_TXP<2>";
137"P3E_CPU0_PE2_SS_C_TXP<1>";
138"P3E_CPU0_PE2_SS_C_TXP<0>";
139"P3E_CPU0_PE2_SS_TXP<1>";
140"P3E_CPU0_PE2_SS_TXP<0>";
%"CAP"
"1","(1125,3650)","2","mstr_discrete","I1";
;
CDS_SEC"1"
ROOM"OCP_STEERING"
CDS_LOCATION"C7G24"
SEC"1"
SEC_TYPE"0402"
CDS_LIB"mstr_discrete"
MATERIAL"X7R"
VOLTAGE"16V"
PACK_TYPE"0402"
TOLERANCE"10%"
VALUE"0.22UF"
PART_NUMBER"A36096-155"
LOCATION"C7G24";
"A"
$PN"1"97;
"B"
$PN"2"93;
%"TAP"
"7","(-100,3100)","0","mstr_standard","I10";
;
HDL_TAP"TRUE"
BODY_TYPE"PLUMBING"
CDS_LIB"mstr_standard";
"B \NAC \NWC"4;
"S \NAC"
BN"12"49;
%"TAP"
"7","(100,3100)","0","mstr_standard","I11";
;
HDL_TAP"TRUE"
BODY_TYPE"PLUMBING"
CDS_LIB"mstr_standard";
"B \NAC \NWC"4;
"S \NAC"
BN"11"78;
%"CAP"
"1","(-100,3650)","2","mstr_discrete","I12";
;
CDS_SEC"1"
ROOM"OCP_STEERING"
CDS_LOCATION"C7G12"
SEC"1"
CDS_LIB"mstr_discrete"
SEC_TYPE"0402"
MATERIAL"X7R"
VOLTAGE"16V"
PACK_TYPE"0402"
TOLERANCE"10%"
VALUE"0.22UF"
PART_NUMBER"A36096-155"
LOCATION"C7G12";
"A"
$PN"1"52;
"B"
$PN"2"49;
%"CAP"
"1","(100,3350)","2","mstr_discrete","I13";
;
CDS_SEC"1"
ROOM"OCP_STEERING"
CDS_LOCATION"C7G13"
SEC"1"
CDS_LIB"mstr_discrete"
SEC_TYPE"0402"
MATERIAL"X7R"
VOLTAGE"16V"
PACK_TYPE"0402"
TOLERANCE"10%"
VALUE"0.22UF"
PART_NUMBER"A36096-155"
LOCATION"C7G13";
"A"
$PN"1"82;
"B"
$PN"2"78;
%"TAP"
"3","(-700,3900)","0","mstr_standard","I14";
;
HDL_TAP"TRUE"
BODY_TYPE"PLUMBING"
CDS_LIB"mstr_standard";
"B \NAC \NWC"8;
"S \NAC"
BN"15"46;
%"TAP"
"7","(-750,4100)","0","mstr_standard","I15";
;
HDL_TAP"TRUE"
BODY_TYPE"PLUMBING"
CDS_LIB"mstr_standard";
"B \NAC \NWC"1;
"S \NAC"
BN"15"53;
%"TAP"
"3","(1925,3900)","0","mstr_standard","I151";
;
HDL_TAP"TRUE"
BODY_TYPE"PLUMBING"
CDS_LIB"mstr_standard";
"B \NAC \NWC"8;
"S \NAC"
BN"2"102;
%"TAP"
"3","(50,4900)","0","mstr_standard","I152";
;
HDL_TAP"TRUE"
BODY_TYPE"PLUMBING"
CDS_LIB"mstr_standard";
"B \NAC \NWC"7;
"S \NAC"
BN"11"121;
%"CAP"
"1","(-1500,975)","2","mstr_discrete","I153";
;
CDS_SEC"1"
ROOM"OCP_STEERING"
CDS_LOCATION"C6B18"
SEC"1"
CDS_LIB"mstr_discrete"
SEC_TYPE"0402"
MATERIAL"X7R"
VOLTAGE"16V"
PACK_TYPE"0402"
TOLERANCE"10%"
VALUE"0.22UF"
PART_NUMBER"A36096-155"
LOCATION"C6B18";
"A"
$PN"1"37;
"B"
$PN"2"30;
%"TAP"
"7","(-1350,1725)","0","mstr_standard","I154";
;
HDL_TAP"TRUE"
BODY_TYPE"PLUMBING"
CDS_LIB"mstr_standard";
"B \NAC \NWC"11;
"S \NAC"
BN"8"39;
%"TAP"
"3","(-2100,1525)","0","mstr_standard","I155";
;
HDL_TAP"TRUE"
BODY_TYPE"PLUMBING"
CDS_LIB"mstr_standard";
"B \NAC \NWC"10;
"S \NAC"
BN"12"21;
%"TAP"
"7","(-2350,1725)","0","mstr_standard","I156";
;
HDL_TAP"TRUE"
BODY_TYPE"PLUMBING"
CDS_LIB"mstr_standard";
"B \NAC \NWC"11;
"S \NAC"
BN"13"22;
%"TAP"
"7","(-2550,1725)","0","mstr_standard","I157";
;
HDL_TAP"TRUE"
BODY_TYPE"PLUMBING"
CDS_LIB"mstr_standard";
"B \NAC \NWC"11;
"S \NAC"
BN"14"24;
%"TAP"
"7","(-2750,1725)","0","mstr_standard","I158";
;
HDL_TAP"TRUE"
BODY_TYPE"PLUMBING"
CDS_LIB"mstr_standard";
"B \NAC \NWC"11;
"S \NAC"
BN"15"18;
%"TAP"
"3","(-1350,2525)","0","mstr_standard","I159";
;
HDL_TAP"TRUE"
BODY_TYPE"PLUMBING"
CDS_LIB"mstr_standard";
"B \NAC \NWC"9;
"S \NAC"
BN"8"44;
%"TAP"
"3","(-500,3900)","0","mstr_standard","I16";
;
HDL_TAP"TRUE"
BODY_TYPE"PLUMBING"
CDS_LIB"mstr_standard";
"B \NAC \NWC"8;
"S \NAC"
BN"14"51;
%"CAP"
"1","(-1350,2275)","2","mstr_discrete","I160";
;
CDS_SEC"1"
ROOM"OCP_STEERING"
CDS_LOCATION"C6B19"
SEC"1"
CDS_LIB"mstr_discrete"
SEC_TYPE"0402"
MATERIAL"X7R"
VOLTAGE"16V"
PACK_TYPE"0402"
TOLERANCE"10%"
VALUE"0.22UF"
PART_NUMBER"A36096-155"
LOCATION"C6B19";
"A"
$PN"1"44;
"B"
$PN"2"39;
%"TAP"
"3","(-1550,2525)","0","mstr_standard","I161";
;
HDL_TAP"TRUE"
BODY_TYPE"PLUMBING"
CDS_LIB"mstr_standard";
"B \NAC \NWC"9;
"S \NAC"
BN"9"42;
%"TAP"
"3","(-1750,2525)","0","mstr_standard","I162";
;
HDL_TAP"TRUE"
BODY_TYPE"PLUMBING"
CDS_LIB"mstr_standard";
"B \NAC \NWC"9;
"S \NAC"
BN"10"43;
%"CAP"
"1","(-1750,2275)","2","mstr_discrete","I163";
;
CDS_SEC"1"
ROOM"OCP_STEERING"
CDS_LOCATION"C6B15"
SEC"1"
CDS_LIB"mstr_discrete"
SEC_TYPE"0402"
MATERIAL"X7R"
VOLTAGE"16V"
PACK_TYPE"0402"
TOLERANCE"10%"
VALUE"0.22UF"
PART_NUMBER"A36096-155"
LOCATION"C6B15";
"A"
$PN"1"43;
"B"
$PN"2"40;
%"TAP"
"3","(-2150,2525)","0","mstr_standard","I164";
;
HDL_TAP"TRUE"
BODY_TYPE"PLUMBING"
CDS_LIB"mstr_standard";
"B \NAC \NWC"9;
"S \NAC"
BN"12"28;
%"TAP"
"3","(-1950,2525)","0","mstr_standard","I165";
;
HDL_TAP"TRUE"
BODY_TYPE"PLUMBING"
CDS_LIB"mstr_standard";
"B \NAC \NWC"9;
"S \NAC"
BN"11"41;
%"CAP"
"1","(-2150,2275)","2","mstr_discrete","I166";
;
CDS_SEC"1"
ROOM"OCP_STEERING"
CDS_LOCATION"C6B11"
SEC"1"
CDS_LIB"mstr_discrete"
SEC_TYPE"0402"
MATERIAL"X7R"
VOLTAGE"16V"
PACK_TYPE"0402"
TOLERANCE"10%"
VALUE"0.22UF"
PART_NUMBER"A36096-155"
LOCATION"C6B11";
"A"
$PN"1"28;
"B"
$PN"2"23;
%"TAP"
"3","(-2350,2525)","0","mstr_standard","I167";
;
HDL_TAP"TRUE"
BODY_TYPE"PLUMBING"
CDS_LIB"mstr_standard";
"B \NAC \NWC"9;
"S \NAC"
BN"13"26;
%"TAP"
"3","(-2550,2525)","0","mstr_standard","I168";
;
HDL_TAP"TRUE"
BODY_TYPE"PLUMBING"
CDS_LIB"mstr_standard";
"B \NAC \NWC"9;
"S \NAC"
BN"14"27;
%"CAP"
"1","(-2550,2275)","2","mstr_discrete","I169";
;
CDS_SEC"1"
ROOM"OCP_STEERING"
CDS_LOCATION"C6B6"
SEC"1"
CDS_LIB"mstr_discrete"
SEC_TYPE"0402"
MATERIAL"X7R"
VOLTAGE"16V"
PACK_TYPE"0402"
TOLERANCE"10%"
VALUE"0.22UF"
PART_NUMBER"A36096-155"
LOCATION"C6B6";
"A"
$PN"1"27;
"B"
$PN"2"24;
%"TAP"
"7","(-550,4100)","0","mstr_standard","I17";
;
HDL_TAP"TRUE"
BODY_TYPE"PLUMBING"
CDS_LIB"mstr_standard";
"B \NAC \NWC"1;
"S \NAC"
BN"14"54;
%"TAP"
"3","(-2750,2525)","0","mstr_standard","I170";
;
HDL_TAP"TRUE"
BODY_TYPE"PLUMBING"
CDS_LIB"mstr_standard";
"B \NAC \NWC"9;
"S \NAC"
BN"15"25;
%"TAP"
"3","(-1300,1525)","0","mstr_standard","I172";
;
HDL_TAP"TRUE"
BODY_TYPE"PLUMBING"
CDS_LIB"mstr_standard";
"B \NAC \NWC"10;
"S \NAC"
BN"8"38;
%"CAP"
"1","(-1300,1275)","2","mstr_discrete","I173";
;
CDS_SEC"1"
ROOM"OCP_STEERING"
CDS_LOCATION"C6B20"
SEC"1"
CDS_LIB"mstr_discrete"
SEC_TYPE"0402"
MATERIAL"X7R"
VOLTAGE"16V"
PACK_TYPE"0402"
TOLERANCE"10%"
VALUE"0.22UF"
PART_NUMBER"A36096-155"
LOCATION"C6B20";
"A"
$PN"1"38;
"B"
$PN"2"31;
%"TAP"
"7","(-1300,725)","0","mstr_standard","I174";
;
HDL_TAP"TRUE"
BODY_TYPE"PLUMBING"
CDS_LIB"mstr_standard";
"B \NAC \NWC"12;
"S \NAC"
BN"8"31;
%"CAP"
"1","(-1550,1975)","2","mstr_discrete","I175";
;
CDS_SEC"1"
ROOM"OCP_STEERING"
CDS_LOCATION"C6B17"
SEC"1"
CDS_LIB"mstr_discrete"
SEC_TYPE"0402"
MATERIAL"X7R"
VOLTAGE"16V"
PACK_TYPE"0402"
TOLERANCE"10%"
VALUE"0.22UF"
PART_NUMBER"A36096-155"
LOCATION"C6B17";
"A"
$PN"1"42;
"B"
$PN"2"36;
%"TAP"
"3","(-1500,1525)","0","mstr_standard","I176";
;
HDL_TAP"TRUE"
BODY_TYPE"PLUMBING"
CDS_LIB"mstr_standard";
"B \NAC \NWC"10;
"S \NAC"
BN"9"37;
%"TAP"
"7","(-1550,1725)","0","mstr_standard","I177";
;
HDL_TAP"TRUE"
BODY_TYPE"PLUMBING"
CDS_LIB"mstr_standard";
"B \NAC \NWC"11;
"S \NAC"
BN"9"36;
%"TAP"
"7","(-1750,1725)","0","mstr_standard","I178";
;
HDL_TAP"TRUE"
BODY_TYPE"PLUMBING"
CDS_LIB"mstr_standard";
"B \NAC \NWC"11;
"S \NAC"
BN"10"40;
%"TAP"
"3","(-1700,1525)","0","mstr_standard","I179";
;
HDL_TAP"TRUE"
BODY_TYPE"PLUMBING"
CDS_LIB"mstr_standard";
"B \NAC \NWC"10;
"S \NAC"
BN"10"34;
%"TAP"
"3","(-300,3900)","0","mstr_standard","I18";
;
HDL_TAP"TRUE"
BODY_TYPE"PLUMBING"
CDS_LIB"mstr_standard";
"B \NAC \NWC"8;
"S \NAC"
BN"13"50;
%"CAP"
"1","(-1700,1275)","2","mstr_discrete","I180";
;
CDS_SEC"1"
ROOM"OCP_STEERING"
CDS_LOCATION"C6B16"
SEC"1"
CDS_LIB"mstr_discrete"
SEC_TYPE"0402"
MATERIAL"X7R"
VOLTAGE"16V"
PACK_TYPE"0402"
TOLERANCE"10%"
VALUE"0.22UF"
PART_NUMBER"A36096-155"
LOCATION"C6B16";
"A"
$PN"1"34;
"B"
$PN"2"32;
%"CAP"
"1","(-1950,1975)","2","mstr_discrete","I181";
;
CDS_SEC"1"
ROOM"OCP_STEERING"
CDS_LOCATION"C6B14"
SEC"1"
CDS_LIB"mstr_discrete"
SEC_TYPE"0402"
MATERIAL"X7R"
VOLTAGE"16V"
PACK_TYPE"0402"
TOLERANCE"10%"
VALUE"0.22UF"
PART_NUMBER"A36096-155"
LOCATION"C6B14";
"A"
$PN"1"41;
"B"
$PN"2"35;
%"TAP"
"3","(-1900,1525)","0","mstr_standard","I182";
;
HDL_TAP"TRUE"
BODY_TYPE"PLUMBING"
CDS_LIB"mstr_standard";
"B \NAC \NWC"10;
"S \NAC"
BN"11"33;
%"TAP"
"7","(-1950,1725)","0","mstr_standard","I183";
;
HDL_TAP"TRUE"
BODY_TYPE"PLUMBING"
CDS_LIB"mstr_standard";
"B \NAC \NWC"11;
"S \NAC"
BN"11"35;
%"TAP"
"7","(-2150,1725)","0","mstr_standard","I184";
;
HDL_TAP"TRUE"
BODY_TYPE"PLUMBING"
CDS_LIB"mstr_standard";
"B \NAC \NWC"11;
"S \NAC"
BN"12"23;
%"CAP"
"1","(-2350,1975)","2","mstr_discrete","I185";
;
CDS_SEC"1"
ROOM"OCP_STEERING"
CDS_LOCATION"C6B9"
SEC"1"
CDS_LIB"mstr_discrete"
SEC_TYPE"0402"
MATERIAL"X7R"
VOLTAGE"16V"
PACK_TYPE"0402"
TOLERANCE"10%"
VALUE"0.22UF"
PART_NUMBER"A36096-155"
LOCATION"C6B9";
"A"
$PN"1"26;
"B"
$PN"2"22;
%"TAP"
"3","(-2300,1525)","0","mstr_standard","I186";
;
HDL_TAP"TRUE"
BODY_TYPE"PLUMBING"
CDS_LIB"mstr_standard";
"B \NAC \NWC"10;
"S \NAC"
BN"13"20;
%"CAP"
"1","(-2100,1275)","2","mstr_discrete","I187";
;
CDS_SEC"1"
ROOM"OCP_STEERING"
CDS_LOCATION"C6B12"
SEC"1"
CDS_LIB"mstr_discrete"
SEC_TYPE"0402"
MATERIAL"X7R"
VOLTAGE"16V"
PACK_TYPE"0402"
TOLERANCE"10%"
VALUE"0.22UF"
PART_NUMBER"A36096-155"
LOCATION"C6B12";
"A"
$PN"1"21;
"B"
$PN"2"16;
%"TAP"
"7","(-1500,725)","0","mstr_standard","I188";
;
HDL_TAP"TRUE"
BODY_TYPE"PLUMBING"
CDS_LIB"mstr_standard";
"B \NAC \NWC"12;
"S \NAC"
BN"9"30;
%"CAP"
"1","(-1900,975)","2","mstr_discrete","I189";
;
CDS_SEC"1"
ROOM"OCP_STEERING"
CDS_LOCATION"C6B13"
SEC"1"
CDS_LIB"mstr_discrete"
SEC_TYPE"0402"
MATERIAL"X7R"
VOLTAGE"16V"
PACK_TYPE"0402"
TOLERANCE"10%"
VALUE"0.22UF"
PART_NUMBER"A36096-155"
LOCATION"C6B13";
"A"
$PN"1"33;
"B"
$PN"2"29;
%"TAP"
"7","(-350,4100)","0","mstr_standard","I19";
;
HDL_TAP"TRUE"
BODY_TYPE"PLUMBING"
CDS_LIB"mstr_standard";
"B \NAC \NWC"1;
"S \NAC"
BN"13"57;
%"TAP"
"7","(-1700,725)","0","mstr_standard","I190";
;
HDL_TAP"TRUE"
BODY_TYPE"PLUMBING"
CDS_LIB"mstr_standard";
"B \NAC \NWC"12;
"S \NAC"
BN"10"32;
%"TAP"
"7","(-1900,725)","0","mstr_standard","I191";
;
HDL_TAP"TRUE"
BODY_TYPE"PLUMBING"
CDS_LIB"mstr_standard";
"B \NAC \NWC"12;
"S \NAC"
BN"11"29;
%"TAP"
"7","(-2100,725)","0","mstr_standard","I192";
;
HDL_TAP"TRUE"
BODY_TYPE"PLUMBING"
CDS_LIB"mstr_standard";
"B \NAC \NWC"12;
"S \NAC"
BN"12"16;
%"CAP"
"1","(-2300,975)","2","mstr_discrete","I193";
;
CDS_SEC"1"
ROOM"OCP_STEERING"
CDS_LOCATION"C6B10"
SEC"1"
CDS_LIB"mstr_discrete"
SEC_TYPE"0402"
MATERIAL"X7R"
VOLTAGE"16V"
PACK_TYPE"0402"
TOLERANCE"10%"
VALUE"0.22UF"
PART_NUMBER"A36096-155"
LOCATION"C6B10";
"A"
$PN"1"20;
"B"
$PN"2"14;
%"TAP"
"7","(-2300,725)","0","mstr_standard","I194";
;
HDL_TAP"TRUE"
BODY_TYPE"PLUMBING"
CDS_LIB"mstr_standard";
"B \NAC \NWC"12;
"S \NAC"
BN"13"14;
%"TAP"
"3","(-2500,1525)","0","mstr_standard","I195";
;
HDL_TAP"TRUE"
BODY_TYPE"PLUMBING"
CDS_LIB"mstr_standard";
"B \NAC \NWC"10;
"S \NAC"
BN"14"19;
%"CAP"
"1","(-2750,1975)","2","mstr_discrete","I196";
;
CDS_SEC"1"
ROOM"OCP_STEERING"
CDS_LOCATION"C6B4"
SEC"1"
CDS_LIB"mstr_discrete"
SEC_TYPE"0402"
MATERIAL"X7R"
VOLTAGE"16V"
PACK_TYPE"0402"
TOLERANCE"10%"
VALUE"0.22UF"
PART_NUMBER"A36096-155"
LOCATION"C6B4";
"A"
$PN"1"25;
"B"
$PN"2"18;
%"TAP"
"3","(-2700,1525)","0","mstr_standard","I197";
;
HDL_TAP"TRUE"
BODY_TYPE"PLUMBING"
CDS_LIB"mstr_standard";
"B \NAC \NWC"10;
"S \NAC"
BN"15"17;
%"CAP"
"1","(-2500,1275)","2","mstr_discrete","I198";
;
CDS_SEC"1"
ROOM"OCP_STEERING"
CDS_LOCATION"C6B8"
SEC"1"
CDS_LIB"mstr_discrete"
SEC_TYPE"0402"
MATERIAL"X7R"
VOLTAGE"16V"
PACK_TYPE"0402"
TOLERANCE"10%"
VALUE"0.22UF"
PART_NUMBER"A36096-155"
LOCATION"C6B8";
"A"
$PN"1"19;
"B"
$PN"2"15;
%"CAP"
"1","(-750,4350)","2","mstr_discrete","I20";
;
CDS_SEC"1"
ROOM"OCP_STEERING"
CDS_LOCATION"C7G5"
SEC"1"
CDS_LIB"mstr_discrete"
SEC_TYPE"0402"
MATERIAL"X7R"
VOLTAGE"16V"
PACK_TYPE"0402"
TOLERANCE"10%"
VALUE"0.22UF"
PART_NUMBER"A36096-155"
LOCATION"C7G5";
"A"
$PN"1"55;
"B"
$PN"2"53;
%"TAP"
"7","(-2500,725)","0","mstr_standard","I200";
;
HDL_TAP"TRUE"
BODY_TYPE"PLUMBING"
CDS_LIB"mstr_standard";
"B \NAC \NWC"12;
"S \NAC"
BN"14"15;
%"CAP"
"1","(-2700,975)","2","mstr_discrete","I201";
;
CDS_SEC"1"
ROOM"OCP_STEERING"
CDS_LOCATION"C6B5"
SEC"1"
CDS_LIB"mstr_discrete"
SEC_TYPE"0402"
MATERIAL"X7R"
VOLTAGE"16V"
PACK_TYPE"0402"
TOLERANCE"10%"
VALUE"0.22UF"
PART_NUMBER"A36096-155"
LOCATION"C6B5";
"A"
$PN"1"17;
"B"
$PN"2"13;
%"TAP"
"7","(-2700,725)","0","mstr_standard","I202";
;
HDL_TAP"TRUE"
BODY_TYPE"PLUMBING"
CDS_LIB"mstr_standard";
"B \NAC \NWC"12;
"S \NAC"
BN"15"13;
%"CAP"
"1","(1800,2025)","2","mstr_discrete","I205";
;
ROOM"OCP_STEERING"
CDS_LOCATION"C3M25"
$SEC"1"
CDS_SEC"1"
CDS_LIB"mstr_discrete"
MATERIAL"X7R"
VOLTAGE"16V"
PACK_TYPE"0402"
TOLERANCE"10%"
VALUE"0.22UF"
PART_NUMBER"A36096-155"
LOCATION"C3M25";
"A"
$PN"1"91;
"B"
$PN"2"73;
%"CAP"
"1","(2400,2325)","2","mstr_discrete","I206";
;
ROOM"OCP_STEERING"
CDS_LOCATION"C3M34"
$SEC"1"
CDS_SEC"1"
CDS_LIB"mstr_discrete"
MATERIAL"X7R"
VOLTAGE"16V"
PACK_TYPE"0402"
TOLERANCE"10%"
VALUE"0.22UF"
PART_NUMBER"A36096-155"
LOCATION"C3M34";
"A"
$PN"1"112;
"B"
$PN"2"110;
%"TAP"
"3","(2400,2575)","0","mstr_standard","I209";
;
HDL_TAP"TRUE"
BODY_TYPE"PLUMBING"
CDS_LIB"mstr_standard";
"B \NAC \NWC"2;
"S \NAC"
BN"8"112;
%"CAP"
"1","(-350,4350)","2","mstr_discrete","I21";
;
CDS_SEC"1"
ROOM"OCP_STEERING"
CDS_LOCATION"C7G9"
SEC"1"
CDS_LIB"mstr_discrete"
SEC_TYPE"0402"
MATERIAL"X7R"
VOLTAGE"16V"
PACK_TYPE"0402"
TOLERANCE"10%"
VALUE"0.22UF"
PART_NUMBER"A36096-155"
LOCATION"C7G9";
"A"
$PN"1"59;
"B"
$PN"2"57;
%"TAP"
"3","(2200,2575)","0","mstr_standard","I210";
;
HDL_TAP"TRUE"
BODY_TYPE"PLUMBING"
CDS_LIB"mstr_standard";
"B \NAC \NWC"2;
"S \NAC"
BN"9"111;
%"TAP"
"3","(2000,2575)","0","mstr_standard","I211";
;
HDL_TAP"TRUE"
BODY_TYPE"PLUMBING"
CDS_LIB"mstr_standard";
"B \NAC \NWC"2;
"S \NAC"
BN"10"92;
%"CAP"
"1","(2000,2325)","2","mstr_discrete","I212";
;
ROOM"OCP_STEERING"
CDS_LOCATION"C3M28"
$SEC"1"
CDS_SEC"1"
CDS_LIB"mstr_discrete"
MATERIAL"X7R"
VOLTAGE"16V"
PACK_TYPE"0402"
TOLERANCE"10%"
VALUE"0.22UF"
PART_NUMBER"A36096-155"
LOCATION"C3M28";
"A"
$PN"1"92;
"B"
$PN"2"76;
%"TAP"
"3","(1800,2575)","0","mstr_standard","I213";
;
HDL_TAP"TRUE"
BODY_TYPE"PLUMBING"
CDS_LIB"mstr_standard";
"B \NAC \NWC"2;
"S \NAC"
BN"11"91;
%"TAP"
"7","(2400,1775)","0","mstr_standard","I214";
;
HDL_TAP"TRUE"
BODY_TYPE"PLUMBING"
CDS_LIB"mstr_standard";
"B \NAC \NWC"5;
"S \NAC"
BN"8"110;
%"TAP"
"3","(2450,1575)","0","mstr_standard","I215";
;
HDL_TAP"TRUE"
BODY_TYPE"PLUMBING"
CDS_LIB"mstr_standard";
"B \NAC \NWC"3;
"S \NAC"
BN"8"108;
%"TAP"
"3","(2250,1575)","0","mstr_standard","I216";
;
HDL_TAP"TRUE"
BODY_TYPE"PLUMBING"
CDS_LIB"mstr_standard";
"B \NAC \NWC"3;
"S \NAC"
BN"9"106;
%"CAP"
"1","(2450,1325)","2","mstr_discrete","I217";
;
ROOM"OCP_STEERING"
CDS_LOCATION"C3M33"
$SEC"1"
CDS_SEC"1"
CDS_LIB"mstr_discrete"
MATERIAL"X7R"
VOLTAGE"16V"
PACK_TYPE"0402"
TOLERANCE"10%"
VALUE"0.22UF"
PART_NUMBER"A36096-155"
LOCATION"C3M33";
"A"
$PN"1"108;
"B"
$PN"2"104;
%"CAP"
"1","(2200,2025)","2","mstr_discrete","I218";
;
ROOM"OCP_STEERING"
CDS_LOCATION"C3M36"
$SEC"1"
CDS_SEC"1"
CDS_LIB"mstr_discrete"
MATERIAL"X7R"
VOLTAGE"16V"
PACK_TYPE"0402"
TOLERANCE"10%"
VALUE"0.22UF"
PART_NUMBER"A36096-155"
LOCATION"C3M36";
"A"
$PN"1"111;
"B"
$PN"2"109;
%"TAP"
"7","(2200,1775)","0","mstr_standard","I219";
;
HDL_TAP"TRUE"
BODY_TYPE"PLUMBING"
CDS_LIB"mstr_standard";
"B \NAC \NWC"5;
"S \NAC"
BN"9"109;
%"CAP"
"1","(-550,4650)","2","mstr_discrete","I22";
;
CDS_SEC"1"
ROOM"OCP_STEERING"
CDS_LOCATION"C7G8"
SEC"1"
CDS_LIB"mstr_discrete"
SEC_TYPE"0402"
MATERIAL"X7R"
VOLTAGE"16V"
PACK_TYPE"0402"
TOLERANCE"10%"
VALUE"0.22UF"
PART_NUMBER"A36096-155"
LOCATION"C7G8";
"A"
$PN"1"56;
"B"
$PN"2"54;
%"TAP"
"7","(2000,1775)","0","mstr_standard","I220";
;
HDL_TAP"TRUE"
BODY_TYPE"PLUMBING"
CDS_LIB"mstr_standard";
"B \NAC \NWC"5;
"S \NAC"
BN"10"76;
%"TAP"
"7","(1800,1775)","0","mstr_standard","I221";
;
HDL_TAP"TRUE"
BODY_TYPE"PLUMBING"
CDS_LIB"mstr_standard";
"B \NAC \NWC"5;
"S \NAC"
BN"11"73;
%"TAP"
"3","(2050,1575)","0","mstr_standard","I222";
;
HDL_TAP"TRUE"
BODY_TYPE"PLUMBING"
CDS_LIB"mstr_standard";
"B \NAC \NWC"3;
"S \NAC"
BN"10"107;
%"CAP"
"1","(2050,1325)","2","mstr_discrete","I223";
;
ROOM"OCP_STEERING"
CDS_LOCATION"C3M32"
$SEC"1"
CDS_SEC"1"
CDS_LIB"mstr_discrete"
MATERIAL"X7R"
VOLTAGE"16V"
PACK_TYPE"0402"
TOLERANCE"10%"
VALUE"0.22UF"
PART_NUMBER"A36096-155"
LOCATION"C3M32";
"A"
$PN"1"107;
"B"
$PN"2"105;
%"TAP"
"3","(1850,1575)","0","mstr_standard","I224";
;
HDL_TAP"TRUE"
BODY_TYPE"PLUMBING"
CDS_LIB"mstr_standard";
"B \NAC \NWC"3;
"S \NAC"
BN"11"72;
%"CAP"
"1","(2250,1025)","2","mstr_discrete","I225";
;
ROOM"OCP_STEERING"
CDS_LOCATION"C3M35"
$SEC"1"
CDS_SEC"1"
CDS_LIB"mstr_discrete"
MATERIAL"X7R"
VOLTAGE"16V"
PACK_TYPE"0402"
TOLERANCE"10%"
VALUE"0.22UF"
PART_NUMBER"A36096-155"
LOCATION"C3M35";
"A"
$PN"1"106;
"B"
$PN"2"103;
%"TAP"
"7","(2250,775)","0","mstr_standard","I226";
;
HDL_TAP"TRUE"
BODY_TYPE"PLUMBING"
CDS_LIB"mstr_standard";
"B \NAC \NWC"6;
"S \NAC"
BN"9"103;
%"TAP"
"7","(2450,775)","0","mstr_standard","I227";
;
HDL_TAP"TRUE"
BODY_TYPE"PLUMBING"
CDS_LIB"mstr_standard";
"B \NAC \NWC"6;
"S \NAC"
BN"8"104;
%"TAP"
"7","(2050,775)","0","mstr_standard","I228";
;
HDL_TAP"TRUE"
BODY_TYPE"PLUMBING"
CDS_LIB"mstr_standard";
"B \NAC \NWC"6;
"S \NAC"
BN"10"105;
%"CAP"
"1","(1850,1025)","2","mstr_discrete","I229";
;
ROOM"OCP_STEERING"
CDS_LOCATION"C3M26"
$SEC"1"
CDS_SEC"1"
CDS_LIB"mstr_discrete"
MATERIAL"X7R"
VOLTAGE"16V"
PACK_TYPE"0402"
TOLERANCE"10%"
VALUE"0.22UF"
PART_NUMBER"A36096-155"
LOCATION"C3M26";
"A"
$PN"1"72;
"B"
$PN"2"64;
%"TAP"
"3","(-100,3900)","0","mstr_standard","I23";
;
HDL_TAP"TRUE"
BODY_TYPE"PLUMBING"
CDS_LIB"mstr_standard";
"B \NAC \NWC"8;
"S \NAC"
BN"12"52;
%"TAP"
"7","(1850,775)","0","mstr_standard","I230";
;
HDL_TAP"TRUE"
BODY_TYPE"PLUMBING"
CDS_LIB"mstr_standard";
"B \NAC \NWC"6;
"S \NAC"
BN"11"64;
%"TAP"
"3","(1600,2575)","0","mstr_standard","I231";
;
HDL_TAP"TRUE"
BODY_TYPE"PLUMBING"
CDS_LIB"mstr_standard";
"B \NAC \NWC"2;
"S \NAC"
BN"12"90;
%"CAP"
"1","(1600,2325)","2","mstr_discrete","I232";
;
ROOM"OCP_STEERING"
CDS_LOCATION"C3M3"
$SEC"1"
CDS_SEC"1"
CDS_LIB"mstr_discrete"
MATERIAL"X7R"
VOLTAGE"16V"
PACK_TYPE"0402"
TOLERANCE"10%"
VALUE"0.22UF"
PART_NUMBER"A36096-155"
LOCATION"C3M3";
"A"
$PN"1"90;
"B"
$PN"2"74;
%"TAP"
"3","(1400,2575)","0","mstr_standard","I233";
;
HDL_TAP"TRUE"
BODY_TYPE"PLUMBING"
CDS_LIB"mstr_standard";
"B \NAC \NWC"2;
"S \NAC"
BN"13"89;
%"CAP"
"1","(1200,2325)","2","mstr_discrete","I234";
;
ROOM"OCP_STEERING"
CDS_LOCATION"C3M11"
$SEC"1"
CDS_SEC"1"
CDS_LIB"mstr_discrete"
MATERIAL"X7R"
VOLTAGE"16V"
PACK_TYPE"0402"
TOLERANCE"10%"
VALUE"0.22UF"
PART_NUMBER"A36096-155"
LOCATION"C3M11";
"A"
$PN"1"88;
"B"
$PN"2"75;
%"TAP"
"3","(1200,2575)","0","mstr_standard","I235";
;
HDL_TAP"TRUE"
BODY_TYPE"PLUMBING"
CDS_LIB"mstr_standard";
"B \NAC \NWC"2;
"S \NAC"
BN"14"88;
%"TAP"
"3","(1000,2575)","0","mstr_standard","I236";
;
HDL_TAP"TRUE"
BODY_TYPE"PLUMBING"
CDS_LIB"mstr_standard";
"B \NAC \NWC"2;
"S \NAC"
BN"15"77;
%"TAP"
"7","(1600,1775)","0","mstr_standard","I238";
;
HDL_TAP"TRUE"
BODY_TYPE"PLUMBING"
CDS_LIB"mstr_standard";
"B \NAC \NWC"5;
"S \NAC"
BN"12"74;
%"CAP"
"1","(1400,2025)","2","mstr_discrete","I239";
;
ROOM"OCP_STEERING"
CDS_LOCATION"C3M13"
$SEC"1"
CDS_SEC"1"
CDS_LIB"mstr_discrete"
MATERIAL"X7R"
VOLTAGE"16V"
PACK_TYPE"0402"
TOLERANCE"10%"
VALUE"0.22UF"
PART_NUMBER"A36096-155"
LOCATION"C3M13";
"A"
$PN"1"89;
"B"
$PN"2"70;
%"TAP"
"7","(-150,4100)","0","mstr_standard","I24";
;
HDL_TAP"TRUE"
BODY_TYPE"PLUMBING"
CDS_LIB"mstr_standard";
"B \NAC \NWC"1;
"S \NAC"
BN"12"58;
%"TAP"
"7","(1400,1775)","0","mstr_standard","I240";
;
HDL_TAP"TRUE"
BODY_TYPE"PLUMBING"
CDS_LIB"mstr_standard";
"B \NAC \NWC"5;
"S \NAC"
BN"13"70;
%"TAP"
"7","(1200,1775)","0","mstr_standard","I241";
;
HDL_TAP"TRUE"
BODY_TYPE"PLUMBING"
CDS_LIB"mstr_standard";
"B \NAC \NWC"5;
"S \NAC"
BN"14"75;
%"TAP"
"3","(1650,1575)","0","mstr_standard","I242";
;
HDL_TAP"TRUE"
BODY_TYPE"PLUMBING"
CDS_LIB"mstr_standard";
"B \NAC \NWC"3;
"S \NAC"
BN"12"71;
%"TAP"
"3","(1450,1575)","0","mstr_standard","I243";
;
HDL_TAP"TRUE"
BODY_TYPE"PLUMBING"
CDS_LIB"mstr_standard";
"B \NAC \NWC"3;
"S \NAC"
BN"13"69;
%"CAP"
"1","(1650,1325)","2","mstr_discrete","I244";
;
ROOM"OCP_STEERING"
CDS_LOCATION"C3M4"
$SEC"1"
CDS_SEC"1"
CDS_LIB"mstr_discrete"
MATERIAL"X7R"
VOLTAGE"16V"
PACK_TYPE"0402"
TOLERANCE"10%"
VALUE"0.22UF"
PART_NUMBER"A36096-155"
LOCATION"C3M4";
"A"
$PN"1"71;
"B"
$PN"2"65;
%"TAP"
"3","(1250,1575)","0","mstr_standard","I245";
;
HDL_TAP"TRUE"
BODY_TYPE"PLUMBING"
CDS_LIB"mstr_standard";
"B \NAC \NWC"3;
"S \NAC"
BN"14"68;
%"CAP"
"1","(1250,1325)","2","mstr_discrete","I246";
;
ROOM"OCP_STEERING"
CDS_LOCATION"C3M12"
$SEC"1"
CDS_SEC"1"
CDS_LIB"mstr_discrete"
MATERIAL"X7R"
VOLTAGE"16V"
PACK_TYPE"0402"
TOLERANCE"10%"
VALUE"0.22UF"
PART_NUMBER"A36096-155"
LOCATION"C3M12";
"A"
$PN"1"68;
"B"
$PN"2"66;
%"CAP"
"1","(1000,2025)","2","mstr_discrete","I247";
;
ROOM"OCP_STEERING"
CDS_LOCATION"C3M2"
$SEC"1"
CDS_SEC"1"
CDS_LIB"mstr_discrete"
MATERIAL"X7R"
VOLTAGE"16V"
PACK_TYPE"0402"
TOLERANCE"10%"
VALUE"0.22UF"
PART_NUMBER"A36096-155"
LOCATION"C3M2";
"A"
$PN"1"77;
"B"
$PN"2"61;
%"TAP"
"7","(1000,1775)","0","mstr_standard","I248";
;
HDL_TAP"TRUE"
BODY_TYPE"PLUMBING"
CDS_LIB"mstr_standard";
"B \NAC \NWC"5;
"S \NAC"
BN"15"61;
%"TAP"
"3","(100,3900)","0","mstr_standard","I25";
;
HDL_TAP"TRUE"
BODY_TYPE"PLUMBING"
CDS_LIB"mstr_standard";
"B \NAC \NWC"8;
"S \NAC"
BN"11"82;
%"TAP"
"3","(1050,1575)","0","mstr_standard","I250";
;
HDL_TAP"TRUE"
BODY_TYPE"PLUMBING"
CDS_LIB"mstr_standard";
"B \NAC \NWC"3;
"S \NAC"
BN"15"67;
%"TAP"
"7","(1450,775)","0","mstr_standard","I251";
;
HDL_TAP"TRUE"
BODY_TYPE"PLUMBING"
CDS_LIB"mstr_standard";
"B \NAC \NWC"6;
"S \NAC"
BN"13"63;
%"TAP"
"7","(1650,775)","0","mstr_standard","I252";
;
HDL_TAP"TRUE"
BODY_TYPE"PLUMBING"
CDS_LIB"mstr_standard";
"B \NAC \NWC"6;
"S \NAC"
BN"12"65;
%"CAP"
"1","(1450,1025)","2","mstr_discrete","I253";
;
ROOM"OCP_STEERING"
CDS_LOCATION"C3M14"
$SEC"1"
CDS_SEC"1"
CDS_LIB"mstr_discrete"
MATERIAL"X7R"
VOLTAGE"16V"
PACK_TYPE"0402"
TOLERANCE"10%"
VALUE"0.22UF"
PART_NUMBER"A36096-155"
LOCATION"C3M14";
"A"
$PN"1"69;
"B"
$PN"2"63;
%"TAP"
"7","(1250,775)","0","mstr_standard","I254";
;
HDL_TAP"TRUE"
BODY_TYPE"PLUMBING"
CDS_LIB"mstr_standard";
"B \NAC \NWC"6;
"S \NAC"
BN"14"66;
%"CAP"
"1","(1050,1025)","2","mstr_discrete","I255";
;
ROOM"OCP_STEERING"
CDS_LOCATION"C3M1"
$SEC"1"
CDS_SEC"1"
CDS_LIB"mstr_discrete"
MATERIAL"X7R"
VOLTAGE"16V"
PACK_TYPE"0402"
TOLERANCE"10%"
VALUE"0.22UF"
PART_NUMBER"A36096-155"
LOCATION"C3M1";
"A"
$PN"1"67;
"B"
$PN"2"62;
%"TAP"
"7","(1050,775)","0","mstr_standard","I256";
;
HDL_TAP"TRUE"
BODY_TYPE"PLUMBING"
CDS_LIB"mstr_standard";
"B \NAC \NWC"6;
"S \NAC"
BN"15"62;
%"TAP"
"7","(50,4100)","0","mstr_standard","I26";
;
HDL_TAP"TRUE"
BODY_TYPE"PLUMBING"
CDS_LIB"mstr_standard";
"B \NAC \NWC"1;
"S \NAC"
BN"11"117;
%"CAP"
"1","(-150,4650)","2","mstr_discrete","I27";
;
CDS_SEC"1"
ROOM"OCP_STEERING"
CDS_LOCATION"C7G11"
SEC"1"
CDS_LIB"mstr_discrete"
SEC_TYPE"0402"
MATERIAL"X7R"
VOLTAGE"16V"
PACK_TYPE"0402"
TOLERANCE"10%"
VALUE"0.22UF"
PART_NUMBER"A36096-155"
LOCATION"C7G11";
"A"
$PN"1"60;
"B"
$PN"2"58;
%"CAP"
"1","(50,4350)","2","mstr_discrete","I28";
;
CDS_SEC"1"
ROOM"OCP_STEERING"
CDS_LOCATION"C7G14"
SEC"1"
CDS_LIB"mstr_discrete"
SEC_TYPE"0402"
MATERIAL"X7R"
VOLTAGE"16V"
PACK_TYPE"0402"
TOLERANCE"10%"
VALUE"0.22UF"
PART_NUMBER"A36096-155"
LOCATION"C7G14";
"A"
$PN"1"121;
"B"
$PN"2"117;
%"TAP"
"7","(300,3100)","0","mstr_standard","I29";
;
HDL_TAP"TRUE"
BODY_TYPE"PLUMBING"
CDS_LIB"mstr_standard";
"B \NAC \NWC"4;
"S \NAC"
BN"10"80;
%"TAP"
"7","(500,3100)","0","mstr_standard","I30";
;
HDL_TAP"TRUE"
BODY_TYPE"PLUMBING"
CDS_LIB"mstr_standard";
"B \NAC \NWC"4;
"S \NAC"
BN"9"79;
%"CAP"
"1","(300,3650)","2","mstr_discrete","I31";
;
CDS_SEC"1"
ROOM"OCP_STEERING"
CDS_LOCATION"C7G16"
SEC"1"
CDS_LIB"mstr_discrete"
SEC_TYPE"0402"
MATERIAL"X7R"
VOLTAGE"16V"
PACK_TYPE"0402"
TOLERANCE"10%"
VALUE"0.22UF"
PART_NUMBER"A36096-155"
LOCATION"C7G16";
"A"
$PN"1"83;
"B"
$PN"2"80;
%"CAP"
"1","(500,3350)","2","mstr_discrete","I32";
;
CDS_SEC"1"
ROOM"OCP_STEERING"
CDS_LOCATION"C7G18"
SEC"1"
CDS_LIB"mstr_discrete"
SEC_TYPE"0402"
MATERIAL"X7R"
VOLTAGE"16V"
PACK_TYPE"0402"
TOLERANCE"10%"
VALUE"0.22UF"
PART_NUMBER"A36096-155"
LOCATION"C7G18";
"A"
$PN"1"81;
"B"
$PN"2"79;
%"TAP"
"7","(700,3100)","0","mstr_standard","I33";
;
HDL_TAP"TRUE"
BODY_TYPE"PLUMBING"
CDS_LIB"mstr_standard";
"B \NAC \NWC"4;
"S \NAC"
BN"8"84;
%"CAP"
"1","(700,3650)","2","mstr_discrete","I34";
;
CDS_SEC"1"
ROOM"OCP_STEERING"
CDS_LOCATION"C7G20"
SEC"1"
CDS_LIB"mstr_discrete"
SEC_TYPE"0402"
MATERIAL"X7R"
VOLTAGE"16V"
PACK_TYPE"0402"
TOLERANCE"10%"
VALUE"0.22UF"
PART_NUMBER"A36096-155"
LOCATION"C7G20";
"A"
$PN"1"87;
"B"
$PN"2"84;
%"TAP"
"7","(925,3100)","0","mstr_standard","I35";
;
HDL_TAP"TRUE"
BODY_TYPE"PLUMBING"
CDS_LIB"mstr_standard";
"B \NAC \NWC"4;
"S \NAC"
BN"7"85;
%"TAP"
"7","(1125,3100)","0","mstr_standard","I36";
;
HDL_TAP"TRUE"
BODY_TYPE"PLUMBING"
CDS_LIB"mstr_standard";
"B \NAC \NWC"4;
"S \NAC"
BN"6"93;
%"CAP"
"1","(925,3350)","2","mstr_discrete","I37";
;
CDS_SEC"1"
ROOM"OCP_STEERING"
CDS_LOCATION"C7G22"
SEC"1"
SEC_TYPE"0402"
CDS_LIB"mstr_discrete"
MATERIAL"X7R"
VOLTAGE"16V"
PACK_TYPE"0402"
TOLERANCE"10%"
VALUE"0.22UF"
PART_NUMBER"A36096-155"
LOCATION"C7G22";
"A"
$PN"1"86;
"B"
$PN"2"85;
%"TAP"
"3","(300,3900)","0","mstr_standard","I38";
;
HDL_TAP"TRUE"
BODY_TYPE"PLUMBING"
CDS_LIB"mstr_standard";
"B \NAC \NWC"8;
"S \NAC"
BN"10"83;
%"TAP"
"7","(250,4100)","0","mstr_standard","I39";
;
HDL_TAP"TRUE"
BODY_TYPE"PLUMBING"
CDS_LIB"mstr_standard";
"B \NAC \NWC"1;
"S \NAC"
BN"10"118;
%"TAP"
"7","(-700,3100)","0","mstr_standard","I4";
;
HDL_TAP"TRUE"
BODY_TYPE"PLUMBING"
CDS_LIB"mstr_standard";
"B \NAC \NWC"4;
"S \NAC"
BN"15"45;
%"TAP"
"3","(500,3900)","0","mstr_standard","I40";
;
HDL_TAP"TRUE"
BODY_TYPE"PLUMBING"
CDS_LIB"mstr_standard";
"B \NAC \NWC"8;
"S \NAC"
BN"9"81;
%"TAP"
"7","(450,4100)","0","mstr_standard","I41";
;
HDL_TAP"TRUE"
BODY_TYPE"PLUMBING"
CDS_LIB"mstr_standard";
"B \NAC \NWC"1;
"S \NAC"
BN"9"119;
%"TAP"
"3","(700,3900)","0","mstr_standard","I42";
;
HDL_TAP"TRUE"
BODY_TYPE"PLUMBING"
CDS_LIB"mstr_standard";
"B \NAC \NWC"8;
"S \NAC"
BN"8"87;
%"TAP"
"7","(650,4100)","0","mstr_standard","I43";
;
HDL_TAP"TRUE"
BODY_TYPE"PLUMBING"
CDS_LIB"mstr_standard";
"B \NAC \NWC"1;
"S \NAC"
BN"8"123;
%"CAP"
"1","(450,4350)","2","mstr_discrete","I44";
;
CDS_SEC"1"
ROOM"OCP_STEERING"
CDS_LOCATION"C7G17"
SEC"1"
CDS_LIB"mstr_discrete"
SEC_TYPE"0402"
MATERIAL"X7R"
VOLTAGE"16V"
PACK_TYPE"0402"
TOLERANCE"10%"
VALUE"0.22UF"
PART_NUMBER"A36096-155"
LOCATION"C7G17";
"A"
$PN"1"120;
"B"
$PN"2"119;
%"CAP"
"1","(250,4650)","2","mstr_discrete","I45";
;
CDS_SEC"1"
ROOM"OCP_STEERING"
CDS_LOCATION"C7G15"
SEC"1"
CDS_LIB"mstr_discrete"
SEC_TYPE"0402"
MATERIAL"X7R"
VOLTAGE"16V"
PACK_TYPE"0402"
TOLERANCE"10%"
VALUE"0.22UF"
PART_NUMBER"A36096-155"
LOCATION"C7G15";
"A"
$PN"1"122;
"B"
$PN"2"118;
%"CAP"
"1","(650,4650)","2","mstr_discrete","I46";
;
CDS_SEC"1"
ROOM"OCP_STEERING"
CDS_LOCATION"C7G19"
SEC"1"
CDS_LIB"mstr_discrete"
SEC_TYPE"0402"
MATERIAL"X7R"
VOLTAGE"16V"
PACK_TYPE"0402"
TOLERANCE"10%"
VALUE"0.22UF"
PART_NUMBER"A36096-155"
LOCATION"C7G19";
"A"
$PN"1"126;
"B"
$PN"2"123;
%"TAP"
"3","(925,3900)","0","mstr_standard","I47";
;
HDL_TAP"TRUE"
BODY_TYPE"PLUMBING"
CDS_LIB"mstr_standard";
"B \NAC \NWC"8;
"S \NAC"
BN"7"86;
%"TAP"
"7","(875,4100)","0","mstr_standard","I48";
;
HDL_TAP"TRUE"
BODY_TYPE"PLUMBING"
CDS_LIB"mstr_standard";
"B \NAC \NWC"1;
"S \NAC"
BN"7"124;
%"TAP"
"7","(1075,4100)","0","mstr_standard","I49";
;
HDL_TAP"TRUE"
BODY_TYPE"PLUMBING"
CDS_LIB"mstr_standard";
"B \NAC \NWC"1;
"S \NAC"
BN"6"128;
%"TAP"
"7","(-500,3100)","0","mstr_standard","I5";
;
HDL_TAP"TRUE"
BODY_TYPE"PLUMBING"
CDS_LIB"mstr_standard";
"B \NAC \NWC"4;
"S \NAC"
BN"14"48;
%"TAP"
"3","(1125,3900)","0","mstr_standard","I50";
;
HDL_TAP"TRUE"
BODY_TYPE"PLUMBING"
CDS_LIB"mstr_standard";
"B \NAC \NWC"8;
"S \NAC"
BN"6"97;
%"CAP"
"1","(875,4350)","2","mstr_discrete","I51";
;
CDS_SEC"1"
ROOM"OCP_STEERING"
CDS_LOCATION"C7G21"
SEC"1"
SEC_TYPE"0402"
CDS_LIB"mstr_discrete"
MATERIAL"X7R"
VOLTAGE"16V"
PACK_TYPE"0402"
TOLERANCE"10%"
VALUE"0.22UF"
PART_NUMBER"A36096-155"
LOCATION"C7G21";
"A"
$PN"1"125;
"B"
$PN"2"124;
%"CAP"
"1","(1075,4650)","2","mstr_discrete","I52";
;
CDS_SEC"1"
ROOM"OCP_STEERING"
CDS_LOCATION"C7G23"
SEC"1"
SEC_TYPE"0402"
CDS_LIB"mstr_discrete"
MATERIAL"X7R"
VOLTAGE"16V"
PACK_TYPE"0402"
TOLERANCE"10%"
VALUE"0.22UF"
PART_NUMBER"A36096-155"
LOCATION"C7G23";
"A"
$PN"1"131;
"B"
$PN"2"128;
%"TAP"
"7","(1525,3100)","0","mstr_standard","I53";
;
HDL_TAP"TRUE"
BODY_TYPE"PLUMBING"
CDS_LIB"mstr_standard";
"B \NAC \NWC"4;
"S \NAC"
BN"4"95;
%"TAP"
"7","(1325,3100)","0","mstr_standard","I54";
;
HDL_TAP"TRUE"
BODY_TYPE"PLUMBING"
CDS_LIB"mstr_standard";
"B \NAC \NWC"4;
"S \NAC"
BN"5"94;
%"CAP"
"1","(1325,3350)","2","mstr_discrete","I55";
;
CDS_SEC"1"
ROOM"OCP_STEERING"
CDS_LOCATION"C7G26"
SEC"1"
SEC_TYPE"0402"
CDS_LIB"mstr_discrete"
MATERIAL"X7R"
VOLTAGE"16V"
PACK_TYPE"0402"
TOLERANCE"10%"
VALUE"0.22UF"
PART_NUMBER"A36096-155"
LOCATION"C7G26";
"A"
$PN"1"96;
"B"
$PN"2"94;
%"CAP"
"1","(1725,3350)","2","mstr_discrete","I56";
;
CDS_SEC"1"
ROOM"OCP_STEERING"
CDS_LOCATION"C8G4"
SEC"1"
SEC_TYPE"0402"
CDS_LIB"mstr_discrete"
MATERIAL"X7R"
VOLTAGE"16V"
PACK_TYPE"0402"
TOLERANCE"10%"
VALUE"0.22UF"
PART_NUMBER"A36096-155"
LOCATION"C8G4";
"A"
$PN"1"101;
"B"
$PN"2"99;
%"TAP"
"7","(1725,3100)","0","mstr_standard","I57";
;
HDL_TAP"TRUE"
BODY_TYPE"PLUMBING"
CDS_LIB"mstr_standard";
"B \NAC \NWC"4;
"S \NAC"
BN"3"99;
%"CAP"
"1","(1525,3650)","2","mstr_discrete","I58";
;
CDS_SEC"1"
ROOM"OCP_STEERING"
CDS_LOCATION"C8G2"
SEC"1"
SEC_TYPE"0402"
CDS_LIB"mstr_discrete"
MATERIAL"X7R"
VOLTAGE"16V"
PACK_TYPE"0402"
TOLERANCE"10%"
VALUE"0.22UF"
PART_NUMBER"A36096-155"
LOCATION"C8G2";
"A"
$PN"1"98;
"B"
$PN"2"95;
%"TAP"
"7","(2125,3100)","0","mstr_standard","I59";
;
HDL_TAP"TRUE"
BODY_TYPE"PLUMBING"
CDS_LIB"mstr_standard";
"B \NAC \NWC"4;
"S \NAC"
BN"1"113;
%"CAP"
"1","(-700,3350)","2","mstr_discrete","I6";
;
ROOM"OCP_STEERING"
CDS_LOCATION"C7G6"
$SEC"1"
CDS_SEC"1"
CDS_LIB"mstr_discrete"
MATERIAL"X7R"
VOLTAGE"16V"
PACK_TYPE"0402"
TOLERANCE"10%"
VALUE"0.22UF"
PART_NUMBER"A36096-155"
LOCATION"C7G6";
"A"
$PN"1"46;
"B"
$PN"2"45;
%"TAP"
"7","(1925,3100)","0","mstr_standard","I60";
;
HDL_TAP"TRUE"
BODY_TYPE"PLUMBING"
CDS_LIB"mstr_standard";
"B \NAC \NWC"4;
"S \NAC"
BN"2"100;
%"CAP"
"1","(1925,3650)","2","mstr_discrete","I61";
;
CDS_SEC"1"
ROOM"OCP_STEERING"
CDS_LOCATION"C8G6"
SEC"1"
SEC_TYPE"0402"
CDS_LIB"mstr_discrete"
MATERIAL"X7R"
VOLTAGE"16V"
PACK_TYPE"0402"
TOLERANCE"10%"
VALUE"0.22UF"
PART_NUMBER"A36096-155"
LOCATION"C8G6";
"A"
$PN"1"102;
"B"
$PN"2"100;
%"CAP"
"1","(2125,3350)","2","mstr_discrete","I62";
;
CDS_SEC"1"
ROOM"OCP_STEERING"
CDS_LOCATION"C8G7"
SEC"1"
SEC_TYPE"0402"
CDS_LIB"mstr_discrete"
MATERIAL"X7R"
VOLTAGE"16V"
PACK_TYPE"0402"
TOLERANCE"10%"
VALUE"0.22UF"
PART_NUMBER"A36096-155"
LOCATION"C8G7";
"A"
$PN"1"115;
"B"
$PN"2"113;
%"TAP"
"3","(1325,3900)","0","mstr_standard","I63";
;
HDL_TAP"TRUE"
BODY_TYPE"PLUMBING"
CDS_LIB"mstr_standard";
"B \NAC \NWC"8;
"S \NAC"
BN"5"96;
%"TAP"
"7","(1275,4100)","0","mstr_standard","I64";
;
HDL_TAP"TRUE"
BODY_TYPE"PLUMBING"
CDS_LIB"mstr_standard";
"B \NAC \NWC"1;
"S \NAC"
BN"5"127;
%"TAP"
"3","(1525,3900)","0","mstr_standard","I65";
;
HDL_TAP"TRUE"
BODY_TYPE"PLUMBING"
CDS_LIB"mstr_standard";
"B \NAC \NWC"8;
"S \NAC"
BN"4"98;
%"TAP"
"7","(1475,4100)","0","mstr_standard","I66";
;
HDL_TAP"TRUE"
BODY_TYPE"PLUMBING"
CDS_LIB"mstr_standard";
"B \NAC \NWC"1;
"S \NAC"
BN"4"129;
%"TAP"
"7","(1675,4100)","0","mstr_standard","I67";
;
HDL_TAP"TRUE"
BODY_TYPE"PLUMBING"
CDS_LIB"mstr_standard";
"B \NAC \NWC"1;
"S \NAC"
BN"3"133;
%"TAP"
"3","(1725,3900)","0","mstr_standard","I68";
;
HDL_TAP"TRUE"
BODY_TYPE"PLUMBING"
CDS_LIB"mstr_standard";
"B \NAC \NWC"8;
"S \NAC"
BN"3"101;
%"CAP"
"1","(1275,4350)","2","mstr_discrete","I69";
;
CDS_SEC"1"
ROOM"OCP_STEERING"
CDS_LOCATION"C7G25"
SEC"1"
SEC_TYPE"0402"
CDS_LIB"mstr_discrete"
MATERIAL"X7R"
VOLTAGE"16V"
PACK_TYPE"0402"
TOLERANCE"10%"
VALUE"0.22UF"
PART_NUMBER"A36096-155"
LOCATION"C7G25";
"A"
$PN"1"130;
"B"
$PN"2"127;
%"CAP"
"1","(-500,3650)","2","mstr_discrete","I7";
;
CDS_SEC"1"
ROOM"OCP_STEERING"
CDS_LOCATION"C7G7"
SEC"1"
CDS_LIB"mstr_discrete"
SEC_TYPE"0402"
MATERIAL"X7R"
VOLTAGE"16V"
PACK_TYPE"0402"
TOLERANCE"10%"
VALUE"0.22UF"
PART_NUMBER"A36096-155"
LOCATION"C7G7";
"A"
$PN"1"51;
"B"
$PN"2"48;
%"CAP"
"1","(1475,4650)","2","mstr_discrete","I70";
;
CDS_SEC"1"
ROOM"OCP_STEERING"
CDS_LOCATION"C8G1"
SEC"1"
SEC_TYPE"0402"
CDS_LIB"mstr_discrete"
MATERIAL"X7R"
VOLTAGE"16V"
PACK_TYPE"0402"
TOLERANCE"10%"
VALUE"0.22UF"
PART_NUMBER"A36096-155"
LOCATION"C8G1";
"A"
$PN"1"132;
"B"
$PN"2"129;
%"CAP"
"1","(1675,4350)","2","mstr_discrete","I71";
;
CDS_SEC"1"
ROOM"OCP_STEERING"
CDS_LOCATION"C8G3"
SEC"1"
SEC_TYPE"0402"
CDS_LIB"mstr_discrete"
MATERIAL"X7R"
VOLTAGE"16V"
PACK_TYPE"0402"
TOLERANCE"10%"
VALUE"0.22UF"
PART_NUMBER"A36096-155"
LOCATION"C8G3";
"A"
$PN"1"135;
"B"
$PN"2"133;
%"TAP"
"7","(1875,4100)","0","mstr_standard","I72";
;
HDL_TAP"TRUE"
BODY_TYPE"PLUMBING"
CDS_LIB"mstr_standard";
"B \NAC \NWC"1;
"S \NAC"
BN"2"134;
%"TAP"
"3","(2125,3900)","0","mstr_standard","I73";
;
HDL_TAP"TRUE"
BODY_TYPE"PLUMBING"
CDS_LIB"mstr_standard";
"B \NAC \NWC"8;
"S \NAC"
BN"1"115;
%"TAP"
"7","(2075,4100)","0","mstr_standard","I74";
;
HDL_TAP"TRUE"
BODY_TYPE"PLUMBING"
CDS_LIB"mstr_standard";
"B \NAC \NWC"1;
"S \NAC"
BN"1"137;
%"CAP"
"1","(1875,4650)","2","mstr_discrete","I75";
;
CDS_SEC"1"
ROOM"OCP_STEERING"
CDS_LOCATION"C8G5"
SEC"1"
SEC_TYPE"0402"
CDS_LIB"mstr_discrete"
MATERIAL"X7R"
VOLTAGE"16V"
PACK_TYPE"0402"
TOLERANCE"10%"
VALUE"0.22UF"
PART_NUMBER"A36096-155"
LOCATION"C8G5";
"A"
$PN"1"136;
"B"
$PN"2"134;
%"CAP"
"1","(2075,4350)","2","mstr_discrete","I76";
;
CDS_SEC"1"
ROOM"OCP_STEERING"
CDS_LOCATION"C8G8"
SEC"1"
SEC_TYPE"0402"
CDS_LIB"mstr_discrete"
MATERIAL"X7R"
VOLTAGE"16V"
PACK_TYPE"0402"
TOLERANCE"10%"
VALUE"0.22UF"
PART_NUMBER"A36096-155"
LOCATION"C8G8";
"A"
$PN"1"139;
"B"
$PN"2"137;
%"TAP"
"3","(-750,4900)","0","mstr_standard","I78";
;
HDL_TAP"TRUE"
BODY_TYPE"PLUMBING"
CDS_LIB"mstr_standard";
"B \NAC \NWC"7;
"S \NAC"
BN"15"55;
%"TAP"
"3","(-550,4900)","0","mstr_standard","I79";
;
HDL_TAP"TRUE"
BODY_TYPE"PLUMBING"
CDS_LIB"mstr_standard";
"B \NAC \NWC"7;
"S \NAC"
BN"14"56;
%"CAP"
"1","(-300,3350)","2","mstr_discrete","I8";
;
CDS_SEC"1"
ROOM"OCP_STEERING"
CDS_LOCATION"C7G10"
SEC"1"
CDS_LIB"mstr_discrete"
SEC_TYPE"0402"
MATERIAL"X7R"
VOLTAGE"16V"
PACK_TYPE"0402"
TOLERANCE"10%"
VALUE"0.22UF"
PART_NUMBER"A36096-155"
LOCATION"C7G10";
"A"
$PN"1"50;
"B"
$PN"2"47;
%"TAP"
"3","(-350,4900)","0","mstr_standard","I80";
;
HDL_TAP"TRUE"
BODY_TYPE"PLUMBING"
CDS_LIB"mstr_standard";
"B \NAC \NWC"7;
"S \NAC"
BN"13"59;
%"TAP"
"3","(-150,4900)","0","mstr_standard","I81";
;
HDL_TAP"TRUE"
BODY_TYPE"PLUMBING"
CDS_LIB"mstr_standard";
"B \NAC \NWC"7;
"S \NAC"
BN"12"60;
%"TAP"
"3","(450,4900)","0","mstr_standard","I82";
;
HDL_TAP"TRUE"
BODY_TYPE"PLUMBING"
CDS_LIB"mstr_standard";
"B \NAC \NWC"7;
"S \NAC"
BN"9"120;
%"TAP"
"3","(250,4900)","0","mstr_standard","I83";
;
HDL_TAP"TRUE"
BODY_TYPE"PLUMBING"
CDS_LIB"mstr_standard";
"B \NAC \NWC"7;
"S \NAC"
BN"10"122;
%"TAP"
"3","(650,4900)","0","mstr_standard","I84";
;
HDL_TAP"TRUE"
BODY_TYPE"PLUMBING"
CDS_LIB"mstr_standard";
"B \NAC \NWC"7;
"S \NAC"
BN"8"126;
%"TAP"
"3","(875,4900)","0","mstr_standard","I85";
;
HDL_TAP"TRUE"
BODY_TYPE"PLUMBING"
CDS_LIB"mstr_standard";
"B \NAC \NWC"7;
"S \NAC"
BN"7"125;
%"TAP"
"3","(1075,4900)","0","mstr_standard","I86";
;
HDL_TAP"TRUE"
BODY_TYPE"PLUMBING"
CDS_LIB"mstr_standard";
"B \NAC \NWC"7;
"S \NAC"
BN"6"131;
%"TAP"
"3","(1275,4900)","0","mstr_standard","I87";
;
HDL_TAP"TRUE"
BODY_TYPE"PLUMBING"
CDS_LIB"mstr_standard";
"B \NAC \NWC"7;
"S \NAC"
BN"5"130;
%"TAP"
"3","(1475,4900)","0","mstr_standard","I88";
;
HDL_TAP"TRUE"
BODY_TYPE"PLUMBING"
CDS_LIB"mstr_standard";
"B \NAC \NWC"7;
"S \NAC"
BN"4"132;
%"TAP"
"3","(1675,4900)","0","mstr_standard","I89";
;
HDL_TAP"TRUE"
BODY_TYPE"PLUMBING"
CDS_LIB"mstr_standard";
"B \NAC \NWC"7;
"S \NAC"
BN"3"135;
%"TAP"
"7","(-300,3100)","0","mstr_standard","I9";
;
HDL_TAP"TRUE"
BODY_TYPE"PLUMBING"
CDS_LIB"mstr_standard";
"B \NAC \NWC"4;
"S \NAC"
BN"13"47;
%"TAP"
"3","(1875,4900)","0","mstr_standard","I90";
;
HDL_TAP"TRUE"
BODY_TYPE"PLUMBING"
CDS_LIB"mstr_standard";
"B \NAC \NWC"7;
"S \NAC"
BN"2"136;
%"TAP"
"3","(2075,4900)","0","mstr_standard","I91";
;
HDL_TAP"TRUE"
BODY_TYPE"PLUMBING"
CDS_LIB"mstr_standard";
"B \NAC \NWC"7;
"S \NAC"
BN"1"139;
%"TAP"
"3","(2275,4900)","0","mstr_standard","I92";
;
HDL_TAP"TRUE"
BODY_TYPE"PLUMBING"
CDS_LIB"mstr_standard";
"B \NAC \NWC"7;
"S \NAC"
BN"0"140;
%"CAP"
"1","(2275,4650)","2","mstr_discrete","I93";
;
CDS_SEC"1"
ROOM"OCP_STEERING"
CDS_LOCATION"C8G9"
SEC"1"
SEC_TYPE"0402"
CDS_LIB"mstr_discrete"
MATERIAL"X7R"
VOLTAGE"16V"
PACK_TYPE"0402"
TOLERANCE"10%"
VALUE"0.22UF"
PART_NUMBER"A36096-155"
LOCATION"C8G9";
"A"
$PN"1"140;
"B"
$PN"2"138;
%"TAP"
"7","(2325,3100)","0","mstr_standard","I94";
;
HDL_TAP"TRUE"
BODY_TYPE"PLUMBING"
CDS_LIB"mstr_standard";
"B \NAC \NWC"4;
"S \NAC"
BN"0"114;
%"CAP"
"1","(2325,3650)","2","mstr_discrete","I96";
;
CDS_SEC"1"
ROOM"OCP_STEERING"
CDS_LOCATION"C8G10"
SEC"1"
SEC_TYPE"0402"
CDS_LIB"mstr_discrete"
MATERIAL"X7R"
VOLTAGE"16V"
PACK_TYPE"0402"
TOLERANCE"10%"
VALUE"0.22UF"
PART_NUMBER"A36096-155"
LOCATION"C8G10";
"A"
$PN"1"116;
"B"
$PN"2"114;
%"TAP"
"3","(2325,3900)","0","mstr_standard","I97";
;
HDL_TAP"TRUE"
BODY_TYPE"PLUMBING"
CDS_LIB"mstr_standard";
"B \NAC \NWC"8;
"S \NAC"
BN"0"116;
%"TAP"
"7","(2275,4100)","0","mstr_standard","I98";
;
HDL_TAP"TRUE"
BODY_TYPE"PLUMBING"
CDS_LIB"mstr_standard";
"B \NAC \NWC"1;
"S \NAC"
BN"0"138;
END.
